(kicad_pcb
	(version 20260206)
	(generator "pcbnew")
	(generator_version "10.0")
	(general
		(thickness 1.6)
		(legacy_teardrops no)
	)
	(paper "A4")
	(title_block
		(title "Wiwynn_Tioga_Pass_MB.brd")
		(comment 1 "Tioga Pass / footprints 3515-3521 of 4770")
	)
	(layers
		(0 "F.Cu" signal "TOP")
		(4 "In1.Cu" signal "L2GND")
		(6 "In2.Cu" signal "L3")
		(8 "In3.Cu" signal "L4GND")
		(10 "In4.Cu" signal "L5")
		(12 "In5.Cu" signal "L6GND")
		(14 "In6.Cu" signal "L7VCC")
		(16 "In7.Cu" signal "L8VCC")
		(18 "In8.Cu" signal "L9GND")
		(20 "In9.Cu" signal "L10")
		(22 "In10.Cu" signal "L11GND")
		(24 "In11.Cu" signal "L12")
		(26 "In12.Cu" signal "L13GND")
		(2 "B.Cu" signal "BOTTOM")
		(9 "F.Adhes" user "F.Adhesive")
		(11 "B.Adhes" user "B.Adhesive")
		(13 "F.Paste" user "Package Geometry/Pastemask Top")
		(15 "B.Paste" user "Package Geometry/Pastemask Bottom")
		(5 "F.SilkS" user "Ref Des/Silkscreen Top")
		(7 "B.SilkS" user "Ref Des/Silkscreen Bottom")
		(1 "F.Mask" user "Board Geometry/Soldermask Top")
		(3 "B.Mask" user "Board Geometry/Soldermask Bottom")
		(17 "Dwgs.User" user "User.Drawings")
		(19 "Cmts.User" user "User.Comments")
		(21 "Eco1.User" user "User.Eco1")
		(23 "Eco2.User" user "User.Eco2")
		(25 "Edge.Cuts" user "Board Geometry/Outline")
		(27 "Margin" user)
		(31 "F.CrtYd" user "Package Geometry/Place Bound Top")
		(29 "B.CrtYd" user "Package Geometry/Place Bound Bottom")
		(35 "F.Fab" user "Ref Des/Assembly Top")
		(33 "B.Fab" user "Ref Des/Assembly Bottom")
	)
	(footprint ""
		(layer "B.Cu")
		(at 269.559532 -145.0086 90)
		(property "Reference" "C5L8"
			(at -1.848866 0.752348 90)
			(unlocked yes)
			(layer "B.SilkS")
			(effects
				(font
					(size 1.27 0.9652)
					(thickness 0.1524)
				)
				(justify mirror)
			)
		)
		(property "Value" ""
			(at 0 0 90)
			(layer "B.Fab")
			(effects
				(font
					(size 1.27 1.27)
				)
				(justify mirror)
			)
		)
		(duplicate_pad_numbers_are_jumpers no)
		(fp_rect
			(start 0.500126 1.598422)
			(end -0.500126 -0.201422)
			(stroke
				(width 0)
				(type default)
			)
			(fill no)
			(layer "B.CrtYd")
		)
		(fp_line
			(start 0.500126 -0.201422)
			(end -0.500126 -0.201422)
			(stroke
				(width 0.1)
				(type default)
			)
			(layer "B.Fab")
		)
		(fp_line
			(start -0.500126 -0.201422)
			(end -0.500126 1.598422)
			(stroke
				(width 0.1)
				(type default)
			)
			(layer "B.Fab")
		)
		(fp_line
			(start 0.500126 1.598422)
			(end 0.500126 -0.201422)
			(stroke
				(width 0.1)
				(type default)
			)
			(layer "B.Fab")
		)
		(fp_line
			(start -0.500126 1.598422)
			(end 0.500126 1.598422)
			(stroke
				(width 0.1)
				(type default)
			)
			(layer "B.Fab")
		)
		(pad "1" smd rect
			(at 0 0)
			(size 0.889 0.9906)
			(layers "B.Cu" "B.Mask" "B.Paste")
			(net "PVDDQ_DEF")
		)
		(pad "2" smd rect
			(at 0 1.397)
			(size 0.889 0.9906)
			(layers "B.Cu" "B.Mask" "B.Paste")
			(net "GND")
		)
		(zone
			(layer "B.Cu")
			(hatch none 0.5)
			(connect_pads
				(clearance 0)
			)
			(min_thickness 0.25)
			(keepout
				(tracks allowed)
				(vias not_allowed)
				(pads allowed)
				(copperpour not_allowed)
				(footprints allowed)
			)
			(placement
				(enabled no)
				(sheetname "")
			)
			(fill
				(thermal_gap 0.5)
				(thermal_bridge_width 0.5)
				(island_removal_mode 0)
			)
			(polygon
				(pts
					(xy 270.512032 -145.5039) (xy 270.004032 -145.5039) (xy 270.004032 -144.5133) (xy 270.512032 -144.5133)
				)
			)
		)
		(zone
			(layer "B.Cu")
			(hatch none 0.5)
			(connect_pads
				(clearance 0)
			)
			(min_thickness 0.25)
			(keepout
				(tracks not_allowed)
				(vias allowed)
				(pads allowed)
				(copperpour not_allowed)
				(footprints allowed)
			)
			(placement
				(enabled no)
				(sheetname "")
			)
			(fill
				(thermal_gap 0.5)
				(thermal_bridge_width 0.5)
				(island_removal_mode 0)
			)
			(polygon
				(pts
					(xy 270.512032 -145.5039) (xy 270.004032 -145.5039) (xy 270.004032 -144.5133) (xy 270.512032 -144.5133)
				)
			)
		)
	)
	(footprint ""
		(layer "B.Cu")
		(at 442.262006 -41.648126 180)
		(property "Reference" "R25W14"
			(at 0 0 0)
			(layer "B.SilkS")
			(hide yes)
			(effects
				(font
					(size 1.27 1.27)
				)
				(justify mirror)
			)
		)
		(property "Value" "*"
			(at -0.064008 -4.108196 180)
			(unlocked yes)
			(layer "B.Fab")
			(hide yes)
			(effects
				(font
					(size 1.27 1.016)
					(thickness 0.1524)
				)
				(justify mirror)
			)
		)
		(property "Device Type" "120R2F-GP_RCL_GP-120R2F-GP,64.A"
			(at -0.064008 -5.632196 180)
			(unlocked yes)
			(layer "B.Fab")
			(hide yes)
			(effects
				(font
					(size 1.27 1.016)
					(thickness 0.1524)
				)
				(justify mirror)
			)
		)
		(duplicate_pad_numbers_are_jumpers no)
		(fp_line
			(start 0.508 -0.9398)
			(end 0.508 0.9398)
			(stroke
				(width 0.1524)
				(type default)
			)
			(layer "B.SilkS")
		)
		(fp_line
			(start -0.508 -0.9398)
			(end 0.508 -0.9398)
			(stroke
				(width 0.1524)
				(type default)
			)
			(layer "B.SilkS")
		)
		(fp_rect
			(start 0.508 0.9398)
			(end -0.508 -0.9398)
			(stroke
				(width 0)
				(type default)
			)
			(fill no)
			(layer "B.CrtYd")
		)
		(fp_rect
			(start 0.508 0.9398)
			(end -0.508 -0.9398)
			(stroke
				(width 0)
				(type default)
			)
			(fill no)
			(layer "B.Fab")
		)
		(pad "1" smd custom
			(at 0 -0.4445)
			(size 0.1397 0.1397)
			(layers "B.Cu" "B.Mask" "B.Paste")
			(net "GND")
			(options
				(clearance outline)
				(anchor circle)
			)
			(primitives
				(gr_poly
					(pts
						(arc
							(start -0.1778 0.2794)
							(mid -0.249642 0.249642)
							(end -0.2794 0.1778)
						)
						(arc
							(start -0.2794 -0.1778)
							(mid -0.249642 -0.249642)
							(end -0.1778 -0.2794)
						)
						(arc
							(start 0.1778 -0.2794)
							(mid 0.249642 -0.249642)
							(end 0.2794 -0.1778)
						)
						(arc
							(start 0.2794 0.1778)
							(mid 0.249642 0.249642)
							(end 0.1778 0.2794)
						)
					)
					(width 0)
					(fill yes)
				)
			)
		)
		(pad "2" smd custom
			(at 0 0.4445)
			(size 0.1397 0.1397)
			(layers "B.Cu" "B.Mask" "B.Paste")
			(net "BMC_M_A2")
			(options
				(clearance outline)
				(anchor circle)
			)
			(primitives
				(gr_poly
					(pts
						(arc
							(start -0.1778 0.2794)
							(mid -0.249642 0.249642)
							(end -0.2794 0.1778)
						)
						(arc
							(start -0.2794 -0.1778)
							(mid -0.249642 -0.249642)
							(end -0.1778 -0.2794)
						)
						(arc
							(start 0.1778 -0.2794)
							(mid 0.249642 -0.249642)
							(end 0.2794 -0.1778)
						)
						(arc
							(start 0.2794 0.1778)
							(mid 0.249642 0.249642)
							(end 0.1778 0.2794)
						)
					)
					(width 0)
					(fill yes)
				)
			)
		)
	)
	(footprint ""
		(layer "B.Cu")
		(at 470.027 -54.991 -90)
		(property "Reference" "R1R23"
			(at 0 0 90)
			(layer "B.SilkS")
			(hide yes)
			(effects
				(font
					(size 1.27 1.27)
				)
				(justify mirror)
			)
		)
		(property "Value" ""
			(at 0 0 90)
			(layer "B.Fab")
			(effects
				(font
					(size 1.27 1.27)
				)
				(justify mirror)
			)
		)
		(duplicate_pad_numbers_are_jumpers no)
		(fp_poly
			(pts
				(xy 0.2794 -0.1016) (xy -0.2794 -0.1016) (xy -0.2794 0.9906) (xy 0.2794 0.9906)
			)
			(stroke
				(width 0)
				(type default)
			)
			(fill no)
			(layer "B.CrtYd")
		)
		(fp_line
			(start -0.2794 0.9906)
			(end -0.2794 -0.1016)
			(stroke
				(width 0.1)
				(type default)
			)
			(layer "B.Fab")
		)
		(fp_line
			(start 0.2794 0.9906)
			(end -0.2794 0.9906)
			(stroke
				(width 0.1)
				(type default)
			)
			(layer "B.Fab")
		)
		(fp_line
			(start -0.2794 -0.1016)
			(end 0.2794 -0.1016)
			(stroke
				(width 0.1)
				(type default)
			)
			(layer "B.Fab")
		)
		(fp_line
			(start 0.2794 -0.1016)
			(end 0.2794 0.9906)
			(stroke
				(width 0.1)
				(type default)
			)
			(layer "B.Fab")
		)
		(pad "1" smd rect
			(at 0 0 90)
			(size 0.508 0.508)
			(layers "B.Cu" "B.Mask" "B.Paste")
			(net "P3V3_STBY")
		)
		(pad "2" smd rect
			(at 0 0.889 90)
			(size 0.508 0.508)
			(layers "B.Cu" "B.Mask" "B.Paste")
			(net "SMB_PCH_MEZZ_LOM3_SCL")
		)
		(zone
			(layer "B.Cu")
			(hatch none 0.5)
			(connect_pads
				(clearance 0)
			)
			(min_thickness 0.25)
			(keepout
				(tracks not_allowed)
				(vias allowed)
				(pads allowed)
				(copperpour not_allowed)
				(footprints allowed)
			)
			(placement
				(enabled no)
				(sheetname "")
			)
			(fill
				(thermal_gap 0.5)
				(thermal_bridge_width 0.5)
				(island_removal_mode 0)
			)
			(polygon
				(pts
					(xy 469.392 -54.737) (xy 469.392 -55.245) (xy 469.773 -55.245) (xy 469.773 -54.737)
				)
			)
		)
		(zone
			(layer "B.Cu")
			(hatch none 0.5)
			(connect_pads
				(clearance 0)
			)
			(min_thickness 0.25)
			(keepout
				(tracks allowed)
				(vias not_allowed)
				(pads allowed)
				(copperpour not_allowed)
				(footprints allowed)
			)
			(placement
				(enabled no)
				(sheetname "")
			)
			(fill
				(thermal_gap 0.5)
				(thermal_bridge_width 0.5)
				(island_removal_mode 0)
			)
			(polygon
				(pts
					(xy 469.773 -54.737) (xy 469.773 -55.245) (xy 469.392 -55.245) (xy 469.392 -54.737)
				)
			)
		)
	)
	(footprint ""
		(layer "B.Cu")
		(at 404.5585 -96.393 -90)
		(property "Reference" "R2N14"
			(at 0 0 90)
			(layer "B.SilkS")
			(hide yes)
			(effects
				(font
					(size 1.27 1.27)
				)
				(justify mirror)
			)
		)
		(property "Value" ""
			(at 0 0 90)
			(layer "B.Fab")
			(effects
				(font
					(size 1.27 1.27)
				)
				(justify mirror)
			)
		)
		(duplicate_pad_numbers_are_jumpers no)
		(fp_poly
			(pts
				(xy 0.2794 -0.1016) (xy -0.2794 -0.1016) (xy -0.2794 0.9906) (xy 0.2794 0.9906)
			)
			(stroke
				(width 0)
				(type default)
			)
			(fill no)
			(layer "B.CrtYd")
		)
		(fp_line
			(start -0.2794 0.9906)
			(end -0.2794 -0.1016)
			(stroke
				(width 0.1)
				(type default)
			)
			(layer "B.Fab")
		)
		(fp_line
			(start 0.2794 0.9906)
			(end -0.2794 0.9906)
			(stroke
				(width 0.1)
				(type default)
			)
			(layer "B.Fab")
		)
		(fp_line
			(start -0.2794 -0.1016)
			(end 0.2794 -0.1016)
			(stroke
				(width 0.1)
				(type default)
			)
			(layer "B.Fab")
		)
		(fp_line
			(start 0.2794 -0.1016)
			(end 0.2794 0.9906)
			(stroke
				(width 0.1)
				(type default)
			)
			(layer "B.Fab")
		)
		(pad "1" smd rect
			(at 0 0 90)
			(size 0.508 0.508)
			(layers "B.Cu" "B.Mask" "B.Paste")
			(net "P3V3_STBY")
		)
		(pad "2" smd rect
			(at 0 0.889 90)
			(size 0.508 0.508)
			(layers "B.Cu" "B.Mask" "B.Paste")
			(net "FM_USB_P0_EN_BOOT_BIOS_STRAP_N")
		)
		(zone
			(layer "B.Cu")
			(hatch none 0.5)
			(connect_pads
				(clearance 0)
			)
			(min_thickness 0.25)
			(keepout
				(tracks not_allowed)
				(vias allowed)
				(pads allowed)
				(copperpour not_allowed)
				(footprints allowed)
			)
			(placement
				(enabled no)
				(sheetname "")
			)
			(fill
				(thermal_gap 0.5)
				(thermal_bridge_width 0.5)
				(island_removal_mode 0)
			)
			(polygon
				(pts
					(xy 403.9235 -96.139) (xy 403.9235 -96.647) (xy 404.3045 -96.647) (xy 404.3045 -96.139)
				)
			)
		)
		(zone
			(layer "B.Cu")
			(hatch none 0.5)
			(connect_pads
				(clearance 0)
			)
			(min_thickness 0.25)
			(keepout
				(tracks allowed)
				(vias not_allowed)
				(pads allowed)
				(copperpour not_allowed)
				(footprints allowed)
			)
			(placement
				(enabled no)
				(sheetname "")
			)
			(fill
				(thermal_gap 0.5)
				(thermal_bridge_width 0.5)
				(island_removal_mode 0)
			)
			(polygon
				(pts
					(xy 404.3045 -96.139) (xy 404.3045 -96.647) (xy 403.9235 -96.647) (xy 403.9235 -96.139)
				)
			)
		)
	)
	(footprint ""
		(layer "B.Cu")
		(at 195.1736 -72.1614 90)
		(property "Reference" "CT37"
			(at 0.8382 -0.84963 90)
			(unlocked yes)
			(layer "B.SilkS")
			(effects
				(font
					(size 0.7874 0.5842)
					(thickness 0.1524)
				)
				(justify left mirror)
			)
		)
		(property "Value" ""
			(at 0 0 90)
			(layer "B.Fab")
			(effects
				(font
					(size 1.27 1.27)
				)
				(justify mirror)
			)
		)
		(duplicate_pad_numbers_are_jumpers no)
		(fp_poly
			(pts
				(xy -0.3048 -0.1016) (xy -0.3048 0.9906) (xy 0.3048 0.9906) (xy 0.3048 -0.1016)
			)
			(stroke
				(width 0)
				(type default)
			)
			(fill no)
			(layer "B.CrtYd")
		)
		(fp_line
			(start 0.3048 -0.1016)
			(end 0.3048 0.9906)
			(stroke
				(width 0.1)
				(type default)
			)
			(layer "B.Fab")
		)
		(fp_line
			(start -0.3048 -0.1016)
			(end 0.3048 -0.1016)
			(stroke
				(width 0.1)
				(type default)
			)
			(layer "B.Fab")
		)
		(fp_line
			(start 0.3048 0.9906)
			(end -0.3048 0.9906)
			(stroke
				(width 0.1)
				(type default)
			)
			(layer "B.Fab")
		)
		(fp_line
			(start -0.3048 0.9906)
			(end -0.3048 -0.1016)
			(stroke
				(width 0.1)
				(type default)
			)
			(layer "B.Fab")
		)
		(pad "1" smd rect
			(at 0 0 270)
			(size 0.508 0.508)
			(layers "B.Cu" "B.Mask" "B.Paste")
			(net "A_TSENSE_PVCCIN_CPU0")
		)
		(pad "2" smd rect
			(at 0 0.889 270)
			(size 0.508 0.508)
			(layers "B.Cu" "B.Mask" "B.Paste")
			(net "GND")
		)
		(zone
			(layer "B.Cu")
			(hatch none 0.5)
			(connect_pads
				(clearance 0)
			)
			(min_thickness 0.25)
			(keepout
				(tracks allowed)
				(vias not_allowed)
				(pads allowed)
				(copperpour not_allowed)
				(footprints allowed)
			)
			(placement
				(enabled no)
				(sheetname "")
			)
			(fill
				(thermal_gap 0.5)
				(thermal_bridge_width 0.5)
				(island_removal_mode 0)
			)
			(polygon
				(pts
					(xy 195.4276 -72.4154) (xy 195.4276 -71.9074) (xy 195.8086 -71.9074) (xy 195.8086 -72.4154)
				)
			)
		)
		(zone
			(layer "B.Cu")
			(hatch none 0.5)
			(connect_pads
				(clearance 0)
			)
			(min_thickness 0.25)
			(keepout
				(tracks not_allowed)
				(vias allowed)
				(pads allowed)
				(copperpour not_allowed)
				(footprints allowed)
			)
			(placement
				(enabled no)
				(sheetname "")
			)
			(fill
				(thermal_gap 0.5)
				(thermal_bridge_width 0.5)
				(island_removal_mode 0)
			)
			(polygon
				(pts
					(xy 195.8086 -72.4154) (xy 195.8086 -71.9074) (xy 195.4276 -71.9074) (xy 195.4276 -72.4154)
				)
			)
		)
	)
	(footprint ""
		(layer "B.Cu")
		(at 385.463034 -27.522932 90)
		(property "Reference" "C2T13"
			(at 0 0 90)
			(layer "B.SilkS")
			(hide yes)
			(effects
				(font
					(size 1.27 1.27)
				)
				(justify mirror)
			)
		)
		(property "Value" ""
			(at 0 0 90)
			(layer "B.Fab")
			(effects
				(font
					(size 1.27 1.27)
				)
				(justify mirror)
			)
		)
		(duplicate_pad_numbers_are_jumpers no)
		(fp_poly
			(pts
				(xy -0.3048 -0.1016) (xy -0.3048 0.9906) (xy 0.3048 0.9906) (xy 0.3048 -0.1016)
			)
			(stroke
				(width 0)
				(type default)
			)
			(fill no)
			(layer "B.CrtYd")
		)
		(fp_line
			(start 0.3048 -0.1016)
			(end 0.3048 0.9906)
			(stroke
				(width 0.1)
				(type default)
			)
			(layer "B.Fab")
		)
		(fp_line
			(start -0.3048 -0.1016)
			(end 0.3048 -0.1016)
			(stroke
				(width 0.1)
				(type default)
			)
			(layer "B.Fab")
		)
		(fp_line
			(start 0.3048 0.9906)
			(end -0.3048 0.9906)
			(stroke
				(width 0.1)
				(type default)
			)
			(layer "B.Fab")
		)
		(fp_line
			(start -0.3048 0.9906)
			(end -0.3048 -0.1016)
			(stroke
				(width 0.1)
				(type default)
			)
			(layer "B.Fab")
		)
		(pad "1" smd rect
			(at 0 0 270)
			(size 0.508 0.508)
			(layers "B.Cu" "B.Mask" "B.Paste")
			(net "P3E_PCH_M2_TX_C_DP<2>")
		)
		(pad "2" smd rect
			(at 0 0.889 270)
			(size 0.508 0.508)
			(layers "B.Cu" "B.Mask" "B.Paste")
			(net "P3E_PCH_M2_TX_DP<2>")
		)
		(zone
			(layer "B.Cu")
			(hatch none 0.5)
			(connect_pads
				(clearance 0)
			)
			(min_thickness 0.25)
			(keepout
				(tracks allowed)
				(vias not_allowed)
				(pads allowed)
				(copperpour not_allowed)
				(footprints allowed)
			)
			(placement
				(enabled no)
				(sheetname "")
			)
			(fill
				(thermal_gap 0.5)
				(thermal_bridge_width 0.5)
				(island_removal_mode 0)
			)
			(polygon
				(pts
					(xy 385.717034 -27.776932) (xy 385.717034 -27.268932) (xy 386.098034 -27.268932) (xy 386.098034 -27.776932)
				)
			)
		)
		(zone
			(layer "B.Cu")
			(hatch none 0.5)
			(connect_pads
				(clearance 0)
			)
			(min_thickness 0.25)
			(keepout
				(tracks not_allowed)
				(vias allowed)
				(pads allowed)
				(copperpour not_allowed)
				(footprints allowed)
			)
			(placement
				(enabled no)
				(sheetname "")
			)
			(fill
				(thermal_gap 0.5)
				(thermal_bridge_width 0.5)
				(island_removal_mode 0)
			)
			(polygon
				(pts
					(xy 386.098034 -27.776932) (xy 386.098034 -27.268932) (xy 385.717034 -27.268932) (xy 385.717034 -27.776932)
				)
			)
		)
	)
	(footprint ""
		(layer "B.Cu")
		(at 195.4784 -102.6414 180)
		(property "Reference" "R6N15"
			(at 0 0 0)
			(layer "B.SilkS")
			(hide yes)
			(effects
				(font
					(size 1.27 1.27)
				)
				(justify mirror)
			)
		)
		(property "Value" ""
			(at 0 0 0)
			(layer "B.Fab")
			(effects
				(font
					(size 1.27 1.27)
				)
				(justify mirror)
			)
		)
		(duplicate_pad_numbers_are_jumpers no)
		(fp_poly
			(pts
				(xy 0.2794 -0.1016) (xy -0.2794 -0.1016) (xy -0.2794 0.9906) (xy 0.2794 0.9906)
			)
			(stroke
				(width 0)
				(type default)
			)
			(fill no)
			(layer "B.CrtYd")
		)
		(fp_line
			(start 0.2794 0.9906)
			(end -0.2794 0.9906)
			(stroke
				(width 0.1)
				(type default)
			)
			(layer "B.Fab")
		)
		(fp_line
			(start 0.2794 -0.1016)
			(end 0.2794 0.9906)
			(stroke
				(width 0.1)
				(type default)
			)
			(layer "B.Fab")
		)
		(fp_line
			(start -0.2794 0.9906)
			(end -0.2794 -0.1016)
			(stroke
				(width 0.1)
				(type default)
			)
			(layer "B.Fab")
		)
		(fp_line
			(start -0.2794 -0.1016)
			(end 0.2794 -0.1016)
			(stroke
				(width 0.1)
				(type default)
			)
			(layer "B.Fab")
		)
		(pad "1" smd rect
			(at 0 0)
			(size 0.508 0.508)
			(layers "B.Cu" "B.Mask" "B.Paste")
			(net "GND")
		)
		(pad "2" smd rect
			(at 0 0.889)
			(size 0.508 0.508)
			(layers "B.Cu" "B.Mask" "B.Paste")
			(net "PD_PIROM_CPU0_ADDR2")
		)
		(zone
			(layer "B.Cu")
			(hatch none 0.5)
			(connect_pads
				(clearance 0)
			)
			(min_thickness 0.25)
			(keepout
				(tracks not_allowed)
				(vias allowed)
				(pads allowed)
				(copperpour not_allowed)
				(footprints allowed)
			)
			(placement
				(enabled no)
				(sheetname "")
			)
			(fill
				(thermal_gap 0.5)
				(thermal_bridge_width 0.5)
				(island_removal_mode 0)
			)
			(polygon
				(pts
					(xy 195.2244 -103.2764) (xy 195.7324 -103.2764) (xy 195.7324 -102.8954) (xy 195.2244 -102.8954)
				)
			)
		)
		(zone
			(layer "B.Cu")
			(hatch none 0.5)
			(connect_pads
				(clearance 0)
			)
			(min_thickness 0.25)
			(keepout
				(tracks allowed)
				(vias not_allowed)
				(pads allowed)
				(copperpour not_allowed)
				(footprints allowed)
			)
			(placement
				(enabled no)
				(sheetname "")
			)
			(fill
				(thermal_gap 0.5)
				(thermal_bridge_width 0.5)
				(island_removal_mode 0)
			)
			(polygon
				(pts
					(xy 195.2244 -102.8954) (xy 195.7324 -102.8954) (xy 195.7324 -103.2764) (xy 195.2244 -103.2764)
				)
			)
		)
	)
)
